# BASEBOARD_FAB2 (Tioga Pass) — schematic netlist excerpt (pin names and nets, part order shuffled) for the footprints in the layout excerpt that follows; sources: Cadence DE-HDL packaged netlist, KiCad conversion of Wiwynn_Tioga_Pass_MB.brd

R2P15  RES  10.0K 1% CHIP  pkg 0402  page 185 : A = P3V3 ; B = FM_M2_SSD_PEDET
C25W20  CAP_A  0.1UF 16V 10% X7R  pkg 0402V  page 145 : A = P2E_SSB_BMC_RX_DP ; B = P2E_SSB_BMC_RX_C_DP

Q1F1  NPN  MMBT3904 IC  pkg SM  page 89
  B  = FM_ADR_COMPLETE_CPU0_R
  E  = GND
  C  = IRQ_DIMM_SAVE_N

(kicad_pcb
	(version 20260206)
	(generator "pcbnew")
	(generator_version "10.0")
	(general
		(thickness 1.6)
		(legacy_teardrops no)
	)
	(paper "A4")
	(title_block
		(title "Wiwynn_Tioga_Pass_MB.brd")
		(comment 1 "Tioga Pass / footprints 868-870 of 4770")
	)
	(layers
		(0 "F.Cu" signal "TOP")
		(4 "In1.Cu" signal "L2GND")
		(6 "In2.Cu" signal "L3")
		(8 "In3.Cu" signal "L4GND")
		(10 "In4.Cu" signal "L5")
		(12 "In5.Cu" signal "L6GND")
		(14 "In6.Cu" signal "L7VCC")
		(16 "In7.Cu" signal "L8VCC")
		(18 "In8.Cu" signal "L9GND")
		(20 "In9.Cu" signal "L10")
		(22 "In10.Cu" signal "L11GND")
		(24 "In11.Cu" signal "L12")
		(26 "In12.Cu" signal "L13GND")
		(2 "B.Cu" signal "BOTTOM")
		(9 "F.Adhes" user "F.Adhesive")
		(11 "B.Adhes" user "B.Adhesive")
		(13 "F.Paste" user "Package Geometry/Pastemask Top")
		(15 "B.Paste" user "Package Geometry/Pastemask Bottom")
		(5 "F.SilkS" user "Ref Des/Silkscreen Top")
		(7 "B.SilkS" user "Ref Des/Silkscreen Bottom")
		(1 "F.Mask" user "Board Geometry/Soldermask Top")
		(3 "B.Mask" user "Board Geometry/Soldermask Bottom")
		(17 "Dwgs.User" user "User.Drawings")
		(19 "Cmts.User" user "User.Comments")
		(21 "Eco1.User" user "User.Eco1")
		(23 "Eco2.User" user "User.Eco2")
		(25 "Edge.Cuts" user "Board Geometry/Outline")
		(27 "Margin" user)
		(31 "F.CrtYd" user "Package Geometry/Place Bound Top")
		(29 "B.CrtYd" user "Package Geometry/Place Bound Bottom")
		(35 "F.Fab" user "Ref Des/Assembly Top")
		(33 "B.Fab" user "Ref Des/Assembly Bottom")
	)
	(footprint ""
		(layer "F.Cu")
		(at 404.241 -82.7405 180)
		(property "Reference" "R2P15"
			(at 0 0 180)
			(layer "F.SilkS")
			(hide yes)
			(effects
				(font
					(size 1.27 1.27)
				)
			)
		)
		(property "Value" ""
			(at 0 0 180)
			(layer "F.Fab")
			(effects
				(font
					(size 1.27 1.27)
				)
			)
		)
		(duplicate_pad_numbers_are_jumpers no)
		(fp_poly
			(pts
				(xy -0.2794 -0.1016) (xy 0.2794 -0.1016) (xy 0.2794 0.9906) (xy -0.2794 0.9906)
			)
			(stroke
				(width 0)
				(type default)
			)
			(fill no)
			(layer "F.CrtYd")
		)
		(fp_line
			(start 0.2794 0.9906)
			(end 0.2794 -0.1016)
			(stroke
				(width 0.1)
				(type default)
			)
			(layer "F.Fab")
		)
		(fp_line
			(start 0.2794 -0.1016)
			(end -0.2794 -0.1016)
			(stroke
				(width 0.1)
				(type default)
			)
			(layer "F.Fab")
		)
		(fp_line
			(start -0.2794 0.9906)
			(end 0.2794 0.9906)
			(stroke
				(width 0.1)
				(type default)
			)
			(layer "F.Fab")
		)
		(fp_line
			(start -0.2794 -0.1016)
			(end -0.2794 0.9906)
			(stroke
				(width 0.1)
				(type default)
			)
			(layer "F.Fab")
		)
		(pad "1" smd rect
			(at 0 0 180)
			(size 0.508 0.508)
			(layers "F.Cu" "F.Mask" "F.Paste")
			(net "P3V3")
		)
		(pad "2" smd rect
			(at 0 0.889 180)
			(size 0.508 0.508)
			(layers "F.Cu" "F.Mask" "F.Paste")
			(net "FM_M2_SSD_PEDET")
		)
		(zone
			(layer "F.Cu")
			(hatch none 0.5)
			(connect_pads
				(clearance 0)
			)
			(min_thickness 0.25)
			(keepout
				(tracks not_allowed)
				(vias allowed)
				(pads allowed)
				(copperpour not_allowed)
				(footprints allowed)
			)
			(placement
				(enabled no)
				(sheetname "")
			)
			(fill
				(thermal_gap 0.5)
				(thermal_bridge_width 0.5)
				(island_removal_mode 0)
			)
			(polygon
				(pts
					(xy 404.495 -83.3755) (xy 403.987 -83.3755) (xy 403.987 -82.9945) (xy 404.495 -82.9945)
				)
			)
		)
		(zone
			(layer "F.Cu")
			(hatch none 0.5)
			(connect_pads
				(clearance 0)
			)
			(min_thickness 0.25)
			(keepout
				(tracks allowed)
				(vias not_allowed)
				(pads allowed)
				(copperpour not_allowed)
				(footprints allowed)
			)
			(placement
				(enabled no)
				(sheetname "")
			)
			(fill
				(thermal_gap 0.5)
				(thermal_bridge_width 0.5)
				(island_removal_mode 0)
			)
			(polygon
				(pts
					(xy 404.495 -82.9945) (xy 403.987 -82.9945) (xy 403.987 -83.3755) (xy 404.495 -83.3755)
				)
			)
		)
	)
	(footprint ""
		(layer "F.Cu")
		(at 309.18785 -32.492696 90)
		(property "Reference" "Q1F1"
			(at -0.229362 -1.2065 90)
			(unlocked yes)
			(layer "F.SilkS")
			(effects
				(font
					(size 0.4064 0.254)
					(thickness 0.1524)
				)
				(justify left)
			)
		)
		(property "Value" ""
			(at 0 0 90)
			(layer "F.Fab")
			(effects
				(font
					(size 1.27 1.27)
				)
			)
		)
		(duplicate_pad_numbers_are_jumpers no)
		(fp_line
			(start 1.778 -0.5715)
			(end 1.778 0.3175)
			(stroke
				(width 0.1524)
				(type default)
			)
			(layer "F.SilkS")
		)
		(fp_line
			(start 0.9525 -0.5715)
			(end 1.778 -0.5715)
			(stroke
				(width 0.1524)
				(type default)
			)
			(layer "F.SilkS")
		)
		(fp_line
			(start 0.381 0.635)
			(end 0.381 1.27)
			(stroke
				(width 0.1524)
				(type default)
			)
			(layer "F.SilkS")
		)
		(fp_line
			(start 1.778 2.4765)
			(end 1.778 1.5875)
			(stroke
				(width 0.1524)
				(type default)
			)
			(layer "F.SilkS")
		)
		(fp_line
			(start 0.9525 2.4765)
			(end 1.778 2.4765)
			(stroke
				(width 0.1524)
				(type default)
			)
			(layer "F.SilkS")
		)
		(fp_circle
			(center -0.9525 -0.9271)
			(end -0.9525 -0.8001)
			(stroke
				(width 0.254)
				(type default)
			)
			(fill no)
			(layer "F.SilkS")
		)
		(fp_poly
			(pts
				(xy 1.778 2.4765) (xy 0.381 2.4765) (xy 0.381 -0.5715) (xy 1.778 -0.5715)
			)
			(stroke
				(width 0)
				(type default)
			)
			(fill no)
			(layer "F.CrtYd")
		)
		(fp_line
			(start 1.778 -0.5715)
			(end 0.381 -0.5715)
			(stroke
				(width 0.1)
				(type default)
			)
			(layer "F.Fab")
		)
		(fp_line
			(start 0.381 -0.5715)
			(end 0.381 2.4765)
			(stroke
				(width 0.1)
				(type default)
			)
			(layer "F.Fab")
		)
		(fp_line
			(start 1.778 2.4765)
			(end 1.778 -0.5715)
			(stroke
				(width 0.1)
				(type default)
			)
			(layer "F.Fab")
		)
		(fp_line
			(start 0.381 2.4765)
			(end 1.778 2.4765)
			(stroke
				(width 0.1)
				(type default)
			)
			(layer "F.Fab")
		)
		(fp_circle
			(center -0.9525 -0.9271)
			(end -0.9525 -0.8001)
			(stroke
				(width 0.254)
				(type default)
			)
			(fill no)
			(layer "F.Fab")
		)
		(pad "1" smd rect
			(at 0 0 90)
			(size 1.143 0.508)
			(layers "F.Cu" "F.Mask" "F.Paste")
			(net "FM_ADR_COMPLETE_CPU0_R")
		)
		(pad "2" smd rect
			(at 0 1.905 90)
			(size 1.143 0.508)
			(layers "F.Cu" "F.Mask" "F.Paste")
			(net "GND")
		)
		(pad "3" smd rect
			(at 2.159 0.9525 90)
			(size 1.143 0.508)
			(layers "F.Cu" "F.Mask" "F.Paste")
			(net "IRQ_DIMM_SAVE_N")
		)
	)
	(footprint ""
		(layer "F.Cu")
		(at 414.962594 -48.083216 180)
		(property "Reference" "C25W20"
			(at -0.8382 -0.67818 180)
			(unlocked yes)
			(layer "F.SilkS")
			(effects
				(font
					(size 0.4064 0.254)
					(thickness 0.1524)
				)
				(justify left)
			)
		)
		(property "Value" ""
			(at 0 0 180)
			(layer "F.Fab")
			(effects
				(font
					(size 1.27 1.27)
				)
			)
		)
		(duplicate_pad_numbers_are_jumpers no)
		(fp_poly
			(pts
				(xy 0.3048 -0.1016) (xy 0.3048 0.9906) (xy -0.3048 0.9906) (xy -0.3048 -0.1016)
			)
			(stroke
				(width 0)
				(type default)
			)
			(fill no)
			(layer "F.CrtYd")
		)
		(fp_line
			(start 0.3048 0.9906)
			(end 0.3048 -0.1016)
			(stroke
				(width 0.1)
				(type default)
			)
			(layer "F.Fab")
		)
		(fp_line
			(start 0.3048 -0.1016)
			(end -0.3048 -0.1016)
			(stroke
				(width 0.1)
				(type default)
			)
			(layer "F.Fab")
		)
		(fp_line
			(start -0.3048 0.9906)
			(end 0.3048 0.9906)
			(stroke
				(width 0.1)
				(type default)
			)
			(layer "F.Fab")
		)
		(fp_line
			(start -0.3048 -0.1016)
			(end -0.3048 0.9906)
			(stroke
				(width 0.1)
				(type default)
			)
			(layer "F.Fab")
		)
		(pad "1" smd rect
			(at 0 0 180)
			(size 0.508 0.508)
			(layers "F.Cu" "F.Mask" "F.Paste")
			(net "P2E_SSB_BMC_RX_DP")
		)
		(pad "2" smd rect
			(at 0 0.889 180)
			(size 0.508 0.508)
			(layers "F.Cu" "F.Mask" "F.Paste")
			(net "P2E_SSB_BMC_RX_C_DP")
		)
		(zone
			(layer "F.Cu")
			(hatch none 0.5)
			(connect_pads
				(clearance 0)
			)
			(min_thickness 0.25)
			(keepout
				(tracks not_allowed)
				(vias allowed)
				(pads allowed)
				(copperpour not_allowed)
				(footprints allowed)
			)
			(placement
				(enabled no)
				(sheetname "")
			)
			(fill
				(thermal_gap 0.5)
				(thermal_bridge_width 0.5)
				(island_removal_mode 0)
			)
			(polygon
				(pts
					(xy 415.216594 -48.718216) (xy 414.708594 -48.718216) (xy 414.708594 -48.337216) (xy 415.216594 -48.337216)
				)
			)
		)
		(zone
			(layer "F.Cu")
			(hatch none 0.5)
			(connect_pads
				(clearance 0)
			)
			(min_thickness 0.25)
			(keepout
				(tracks allowed)
				(vias not_allowed)
				(pads allowed)
				(copperpour not_allowed)
				(footprints allowed)
			)
			(placement
				(enabled no)
				(sheetname "")
			)
			(fill
				(thermal_gap 0.5)
				(thermal_bridge_width 0.5)
				(island_removal_mode 0)
			)
			(polygon
				(pts
					(xy 415.216594 -48.337216) (xy 414.708594 -48.337216) (xy 414.708594 -48.718216) (xy 415.216594 -48.718216)
				)
			)
		)
	)
)
